(kicad_pcb
	(version 20260206)
	(generator "pcbnew")
	(generator_version "10.0")
	(general
		(thickness 1.6)
		(legacy_teardrops no)
	)
	(paper "A4")
	(title_block
		(title "01162023_DA0F0TEBIF0_F0T_Expander_BD_F_brd_V02_OCP.brd")
		(comment 1 "Grand Teton / footprints 4221-4228 of 9728")
	)
	(layers
		(0 "F.Cu" signal "TOP")
		(4 "In1.Cu" signal "GND")
		(6 "In2.Cu" signal "VCC")
		(8 "In3.Cu" signal "VCC1")
		(10 "In4.Cu" signal "GND1")
		(12 "In5.Cu" signal "IN1")
		(14 "In6.Cu" signal "GND2")
		(16 "In7.Cu" signal "IN2")
		(18 "In8.Cu" signal "GND3")
		(20 "In9.Cu" signal "IN3")
		(22 "In10.Cu" signal "GND4")
		(24 "In11.Cu" signal "IN4")
		(26 "In12.Cu" signal "GND5")
		(28 "In13.Cu" signal "IN5")
		(30 "In14.Cu" signal "GND6")
		(32 "In15.Cu" signal "IN6")
		(34 "In16.Cu" signal "GND7")
		(2 "B.Cu" signal "BOTTOM")
		(9 "F.Adhes" user "F.Adhesive")
		(11 "B.Adhes" user "B.Adhesive")
		(13 "F.Paste" user "Package Geometry/Pastemask Top")
		(15 "B.Paste" user "Package Geometry/Pastemask Bottom")
		(5 "F.SilkS" user "Ref Des/Silkscreen Top")
		(7 "B.SilkS" user "Ref Des/Silkscreen Bottom")
		(1 "F.Mask" user "Board Geometry/Soldermask Top")
		(3 "B.Mask" user "Board Geometry/Soldermask Bottom")
		(17 "Dwgs.User" user "User.Drawings")
		(19 "Cmts.User" user "User.Comments")
		(21 "Eco1.User" user "User.Eco1")
		(23 "Eco2.User" user "User.Eco2")
		(25 "Edge.Cuts" user "Board Geometry/Outline")
		(27 "Margin" user)
		(31 "F.CrtYd" user "Package Geometry/Place Bound Top")
		(29 "B.CrtYd" user "Package Geometry/Place Bound Bottom")
		(35 "F.Fab" user "Ref Des/Assembly Top")
		(33 "B.Fab" user "Ref Des/Assembly Bottom")
	)
	(footprint ""
		(layer "F.Cu")
		(at 140.761974 -187.593732)
		(property "Reference" "C4496"
			(at 0 0 0)
			(layer "F.SilkS")
			(hide yes)
			(effects
				(font
					(size 1.27 1.27)
				)
			)
		)
		(property "Value" ""
			(at 0 0 0)
			(layer "F.Fab")
			(effects
				(font
					(size 1.27 1.27)
				)
			)
		)
		(duplicate_pad_numbers_are_jumpers no)
		(fp_line
			(start -0.7874 -0.4064)
			(end 0.7874 -0.4064)
			(stroke
				(width 0.1524)
				(type default)
			)
			(layer "F.SilkS")
		)
		(fp_line
			(start -0.7874 0.4064)
			(end -0.7874 -0.4064)
			(stroke
				(width 0.1524)
				(type default)
			)
			(layer "F.SilkS")
		)
		(fp_line
			(start 0.7874 -0.4064)
			(end 0.7874 0.4064)
			(stroke
				(width 0.1524)
				(type default)
			)
			(layer "F.SilkS")
		)
		(fp_line
			(start 0.7874 0.4064)
			(end -0.7874 0.4064)
			(stroke
				(width 0.1524)
				(type default)
			)
			(layer "F.SilkS")
		)
		(fp_line
			(start -0.67945 -0.305054)
			(end -0.12065 -0.305054)
			(stroke
				(width 0.1)
				(type default)
			)
			(layer "F.Fab")
		)
		(fp_line
			(start -0.67945 0.3048)
			(end -0.67945 -0.305054)
			(stroke
				(width 0.1)
				(type default)
			)
			(layer "F.Fab")
		)
		(fp_line
			(start -0.12065 -0.305054)
			(end -0.12065 -0.2794)
			(stroke
				(width 0.1)
				(type default)
			)
			(layer "F.Fab")
		)
		(fp_line
			(start -0.12065 -0.2794)
			(end 0.12065 -0.2794)
			(stroke
				(width 0.1)
				(type default)
			)
			(layer "F.Fab")
		)
		(fp_line
			(start -0.12065 0.2794)
			(end -0.12065 0.3048)
			(stroke
				(width 0.1)
				(type default)
			)
			(layer "F.Fab")
		)
		(fp_line
			(start -0.12065 0.3048)
			(end -0.67945 0.3048)
			(stroke
				(width 0.1)
				(type default)
			)
			(layer "F.Fab")
		)
		(fp_line
			(start 0.120396 0.2794)
			(end -0.12065 0.2794)
			(stroke
				(width 0.1)
				(type default)
			)
			(layer "F.Fab")
		)
		(fp_line
			(start 0.120396 0.3048)
			(end 0.120396 0.2794)
			(stroke
				(width 0.1)
				(type default)
			)
			(layer "F.Fab")
		)
		(fp_line
			(start 0.12065 -0.3048)
			(end 0.67945 -0.3048)
			(stroke
				(width 0.1)
				(type default)
			)
			(layer "F.Fab")
		)
		(fp_line
			(start 0.12065 -0.2794)
			(end 0.12065 -0.3048)
			(stroke
				(width 0.1)
				(type default)
			)
			(layer "F.Fab")
		)
		(fp_line
			(start 0.67945 -0.3048)
			(end 0.67945 0.3048)
			(stroke
				(width 0.1)
				(type default)
			)
			(layer "F.Fab")
		)
		(fp_line
			(start 0.67945 0.3048)
			(end 0.120396 0.3048)
			(stroke
				(width 0.1)
				(type default)
			)
			(layer "F.Fab")
		)
		(pad "1" smd circle
			(at -0.40005 0)
			(size 0 0)
			(layers "F.Cu" "F.Mask" "F.Paste")
			(net "NIC5_CLK_EN_R_N")
		)
		(pad "2" smd circle
			(at 0.40005 0)
			(size 0 0)
			(layers "F.Cu" "F.Mask" "F.Paste")
			(net "GND")
		)
	)
	(footprint ""
		(layer "F.Cu")
		(at 26.267918 -54.067456)
		(property "Reference" "PR209"
			(at 0 0 0)
			(layer "F.SilkS")
			(hide yes)
			(effects
				(font
					(size 1.27 1.27)
				)
			)
		)
		(property "Value" ""
			(at 0 0 0)
			(layer "F.Fab")
			(effects
				(font
					(size 1.27 1.27)
				)
			)
		)
		(duplicate_pad_numbers_are_jumpers no)
		(fp_line
			(start -0.7874 -0.4064)
			(end 0.7874 -0.4064)
			(stroke
				(width 0.1524)
				(type default)
			)
			(layer "F.SilkS")
		)
		(fp_line
			(start -0.7874 0.4064)
			(end -0.7874 -0.4064)
			(stroke
				(width 0.1524)
				(type default)
			)
			(layer "F.SilkS")
		)
		(fp_line
			(start 0.7874 -0.4064)
			(end 0.7874 0.4064)
			(stroke
				(width 0.1524)
				(type default)
			)
			(layer "F.SilkS")
		)
		(fp_line
			(start 0.7874 0.4064)
			(end -0.7874 0.4064)
			(stroke
				(width 0.1524)
				(type default)
			)
			(layer "F.SilkS")
		)
		(fp_line
			(start -0.67945 -0.305054)
			(end -0.12065 -0.305054)
			(stroke
				(width 0.1)
				(type default)
			)
			(layer "F.Fab")
		)
		(fp_line
			(start -0.67945 0.3048)
			(end -0.67945 -0.305054)
			(stroke
				(width 0.1)
				(type default)
			)
			(layer "F.Fab")
		)
		(fp_line
			(start -0.12065 -0.305054)
			(end -0.12065 -0.2794)
			(stroke
				(width 0.1)
				(type default)
			)
			(layer "F.Fab")
		)
		(fp_line
			(start -0.12065 -0.2794)
			(end 0.12065 -0.2794)
			(stroke
				(width 0.1)
				(type default)
			)
			(layer "F.Fab")
		)
		(fp_line
			(start -0.12065 0.2794)
			(end -0.12065 0.3048)
			(stroke
				(width 0.1)
				(type default)
			)
			(layer "F.Fab")
		)
		(fp_line
			(start -0.12065 0.3048)
			(end -0.67945 0.3048)
			(stroke
				(width 0.1)
				(type default)
			)
			(layer "F.Fab")
		)
		(fp_line
			(start 0.120396 0.2794)
			(end -0.12065 0.2794)
			(stroke
				(width 0.1)
				(type default)
			)
			(layer "F.Fab")
		)
		(fp_line
			(start 0.120396 0.3048)
			(end 0.120396 0.2794)
			(stroke
				(width 0.1)
				(type default)
			)
			(layer "F.Fab")
		)
		(fp_line
			(start 0.12065 -0.3048)
			(end 0.67945 -0.3048)
			(stroke
				(width 0.1)
				(type default)
			)
			(layer "F.Fab")
		)
		(fp_line
			(start 0.12065 -0.2794)
			(end 0.12065 -0.3048)
			(stroke
				(width 0.1)
				(type default)
			)
			(layer "F.Fab")
		)
		(fp_line
			(start 0.67945 -0.3048)
			(end 0.67945 0.3048)
			(stroke
				(width 0.1)
				(type default)
			)
			(layer "F.Fab")
		)
		(fp_line
			(start 0.67945 0.3048)
			(end 0.120396 0.3048)
			(stroke
				(width 0.1)
				(type default)
			)
			(layer "F.Fab")
		)
		(pad "1" smd circle
			(at -0.40005 0)
			(size 0 0)
			(layers "F.Cu" "F.Mask" "F.Paste")
			(net "P12V_SSD0_OCP")
		)
		(pad "2" smd circle
			(at 0.40005 0)
			(size 0 0)
			(layers "F.Cu" "F.Mask" "F.Paste")
			(net "GND")
		)
	)
	(footprint ""
		(layer "F.Cu")
		(at 352.920554 -83.787234)
		(property "Reference" "R1625"
			(at 0 0 0)
			(layer "F.SilkS")
			(hide yes)
			(effects
				(font
					(size 1.27 1.27)
				)
			)
		)
		(property "Value" ""
			(at 0 0 0)
			(layer "F.Fab")
			(effects
				(font
					(size 1.27 1.27)
				)
			)
		)
		(duplicate_pad_numbers_are_jumpers no)
		(fp_line
			(start -0.7874 -0.4064)
			(end 0.7874 -0.4064)
			(stroke
				(width 0.1524)
				(type default)
			)
			(layer "F.SilkS")
		)
		(fp_line
			(start -0.7874 0.4064)
			(end -0.7874 -0.4064)
			(stroke
				(width 0.1524)
				(type default)
			)
			(layer "F.SilkS")
		)
		(fp_line
			(start 0.7874 -0.4064)
			(end 0.7874 0.4064)
			(stroke
				(width 0.1524)
				(type default)
			)
			(layer "F.SilkS")
		)
		(fp_line
			(start 0.7874 0.4064)
			(end -0.7874 0.4064)
			(stroke
				(width 0.1524)
				(type default)
			)
			(layer "F.SilkS")
		)
		(fp_line
			(start -0.67945 -0.305054)
			(end -0.12065 -0.305054)
			(stroke
				(width 0.1)
				(type default)
			)
			(layer "F.Fab")
		)
		(fp_line
			(start -0.67945 0.3048)
			(end -0.67945 -0.305054)
			(stroke
				(width 0.1)
				(type default)
			)
			(layer "F.Fab")
		)
		(fp_line
			(start -0.12065 -0.305054)
			(end -0.12065 -0.2794)
			(stroke
				(width 0.1)
				(type default)
			)
			(layer "F.Fab")
		)
		(fp_line
			(start -0.12065 -0.2794)
			(end 0.12065 -0.2794)
			(stroke
				(width 0.1)
				(type default)
			)
			(layer "F.Fab")
		)
		(fp_line
			(start -0.12065 0.2794)
			(end -0.12065 0.3048)
			(stroke
				(width 0.1)
				(type default)
			)
			(layer "F.Fab")
		)
		(fp_line
			(start -0.12065 0.3048)
			(end -0.67945 0.3048)
			(stroke
				(width 0.1)
				(type default)
			)
			(layer "F.Fab")
		)
		(fp_line
			(start 0.120396 0.2794)
			(end -0.12065 0.2794)
			(stroke
				(width 0.1)
				(type default)
			)
			(layer "F.Fab")
		)
		(fp_line
			(start 0.120396 0.3048)
			(end 0.120396 0.2794)
			(stroke
				(width 0.1)
				(type default)
			)
			(layer "F.Fab")
		)
		(fp_line
			(start 0.12065 -0.3048)
			(end 0.67945 -0.3048)
			(stroke
				(width 0.1)
				(type default)
			)
			(layer "F.Fab")
		)
		(fp_line
			(start 0.12065 -0.2794)
			(end 0.12065 -0.3048)
			(stroke
				(width 0.1)
				(type default)
			)
			(layer "F.Fab")
		)
		(fp_line
			(start 0.67945 -0.3048)
			(end 0.67945 0.3048)
			(stroke
				(width 0.1)
				(type default)
			)
			(layer "F.Fab")
		)
		(fp_line
			(start 0.67945 0.3048)
			(end 0.120396 0.3048)
			(stroke
				(width 0.1)
				(type default)
			)
			(layer "F.Fab")
		)
		(pad "1" smd circle
			(at -0.40005 0)
			(size 0 0)
			(layers "F.Cu" "F.Mask" "F.Paste")
			(net "SMB_BIC_I2C9_MUX1_SSD10_R_SCL")
		)
		(pad "2" smd circle
			(at 0.40005 0)
			(size 0 0)
			(layers "F.Cu" "F.Mask" "F.Paste")
			(net "SMB_BIC_I2C9_MUX1_SSD10_SCL")
		)
	)
	(footprint ""
		(layer "F.Cu")
		(at 324.15861 -111.227108 90)
		(property "Reference" "PC323"
			(at 0 0 90)
			(layer "F.SilkS")
			(hide yes)
			(effects
				(font
					(size 1.27 1.27)
				)
			)
		)
		(property "Value" ""
			(at 0 0 90)
			(layer "F.Fab")
			(effects
				(font
					(size 1.27 1.27)
				)
			)
		)
		(duplicate_pad_numbers_are_jumpers no)
		(fp_line
			(start 1.524 -0.762)
			(end 1.524 0.762)
			(stroke
				(width 0.1524)
				(type default)
			)
			(layer "F.SilkS")
		)
		(fp_line
			(start -1.524 -0.762)
			(end 1.524 -0.762)
			(stroke
				(width 0.1524)
				(type default)
			)
			(layer "F.SilkS")
		)
		(fp_line
			(start 1.524 0.762)
			(end -1.524 0.762)
			(stroke
				(width 0.1524)
				(type default)
			)
			(layer "F.SilkS")
		)
		(fp_line
			(start -1.524 0.762)
			(end -1.524 -0.762)
			(stroke
				(width 0.1524)
				(type default)
			)
			(layer "F.SilkS")
		)
		(fp_line
			(start 1.1049 -0.724916)
			(end -1.1049 -0.724916)
			(stroke
				(width 0.1)
				(type default)
			)
			(layer "F.Fab")
		)
		(fp_line
			(start -1.1049 -0.724916)
			(end -1.1049 0.724916)
			(stroke
				(width 0.1)
				(type default)
			)
			(layer "F.Fab")
		)
		(fp_line
			(start 1.1049 0.724916)
			(end 1.1049 -0.724916)
			(stroke
				(width 0.1)
				(type default)
			)
			(layer "F.Fab")
		)
		(fp_line
			(start -1.1049 0.724916)
			(end 1.1049 0.724916)
			(stroke
				(width 0.1)
				(type default)
			)
			(layer "F.Fab")
		)
		(pad "1" smd rect
			(at -0.889 0 270)
			(size 1.016 1.27)
			(layers "F.Cu" "F.Mask" "F.Paste")
			(net "P12V_NIC5_R")
		)
		(pad "2" smd rect
			(at 0.889 0 270)
			(size 1.016 1.27)
			(layers "F.Cu" "F.Mask" "F.Paste")
			(net "GND")
		)
	)
	(footprint ""
		(layer "F.Cu")
		(at 476.681038 -554.52518 180)
		(property "Reference" "J55_12"
			(at -2.8448 -1.402334 0)
			(unlocked yes)
			(layer "B.SilkS")
			(effects
				(font
					(size 0.7874 0.5842)
					(thickness 0.1524)
				)
				(justify mirror)
			)
		)
		(property "Value" ""
			(at 0 0 180)
			(layer "F.Fab")
			(effects
				(font
					(size 1.27 1.27)
				)
			)
		)
		(duplicate_pad_numbers_are_jumpers no)
		(pad "1" thru_hole circle
			(at 0 0 180)
			(size 0.4572 0.4572)
			(drill 0.2032)
			(layers "*.Cu" "*.Mask")
			(remove_unused_layers no)
			(net "Net_2678")
			(clearance 0.127)
			(thermal_gap 0.127)
			(padstack
				(mode front_inner_back)
				(layer "Inner"
					(shape circle)
					(size 0.4572 0.4572)
					(clearance 0.127)
				)
				(layer "B.Cu"
					(shape circle)
					(size 0.508 0.508)
					(clearance 0.1016)
				)
			)
		)
	)
	(footprint ""
		(layer "F.Cu")
		(at 366.566196 -285.088584 90)
		(property "Reference" "PC187"
			(at 0 0 90)
			(layer "F.SilkS")
			(hide yes)
			(effects
				(font
					(size 1.27 1.27)
				)
			)
		)
		(property "Value" ""
			(at 0 0 90)
			(layer "F.Fab")
			(effects
				(font
					(size 1.27 1.27)
				)
			)
		)
		(duplicate_pad_numbers_are_jumpers no)
		(fp_line
			(start 0.7874 -0.4064)
			(end 0.7874 0.4064)
			(stroke
				(width 0.1524)
				(type default)
			)
			(layer "F.SilkS")
		)
		(fp_line
			(start -0.7874 -0.4064)
			(end 0.7874 -0.4064)
			(stroke
				(width 0.1524)
				(type default)
			)
			(layer "F.SilkS")
		)
		(fp_line
			(start 0.7874 0.4064)
			(end -0.7874 0.4064)
			(stroke
				(width 0.1524)
				(type default)
			)
			(layer "F.SilkS")
		)
		(fp_line
			(start -0.7874 0.4064)
			(end -0.7874 -0.4064)
			(stroke
				(width 0.1524)
				(type default)
			)
			(layer "F.SilkS")
		)
		(fp_line
			(start -0.12065 -0.305054)
			(end -0.12065 -0.2794)
			(stroke
				(width 0.1)
				(type default)
			)
			(layer "F.Fab")
		)
		(fp_line
			(start -0.67945 -0.305054)
			(end -0.12065 -0.305054)
			(stroke
				(width 0.1)
				(type default)
			)
			(layer "F.Fab")
		)
		(fp_line
			(start 0.67945 -0.3048)
			(end 0.67945 0.3048)
			(stroke
				(width 0.1)
				(type default)
			)
			(layer "F.Fab")
		)
		(fp_line
			(start 0.12065 -0.3048)
			(end 0.67945 -0.3048)
			(stroke
				(width 0.1)
				(type default)
			)
			(layer "F.Fab")
		)
		(fp_line
			(start 0.12065 -0.2794)
			(end 0.12065 -0.3048)
			(stroke
				(width 0.1)
				(type default)
			)
			(layer "F.Fab")
		)
		(fp_line
			(start -0.12065 -0.2794)
			(end 0.12065 -0.2794)
			(stroke
				(width 0.1)
				(type default)
			)
			(layer "F.Fab")
		)
		(fp_line
			(start 0.120396 0.2794)
			(end -0.12065 0.2794)
			(stroke
				(width 0.1)
				(type default)
			)
			(layer "F.Fab")
		)
		(fp_line
			(start -0.12065 0.2794)
			(end -0.12065 0.3048)
			(stroke
				(width 0.1)
				(type default)
			)
			(layer "F.Fab")
		)
		(fp_line
			(start 0.67945 0.3048)
			(end 0.120396 0.3048)
			(stroke
				(width 0.1)
				(type default)
			)
			(layer "F.Fab")
		)
		(fp_line
			(start 0.120396 0.3048)
			(end 0.120396 0.2794)
			(stroke
				(width 0.1)
				(type default)
			)
			(layer "F.Fab")
		)
		(fp_line
			(start -0.12065 0.3048)
			(end -0.67945 0.3048)
			(stroke
				(width 0.1)
				(type default)
			)
			(layer "F.Fab")
		)
		(fp_line
			(start -0.67945 0.3048)
			(end -0.67945 -0.305054)
			(stroke
				(width 0.1)
				(type default)
			)
			(layer "F.Fab")
		)
		(pad "1" smd circle
			(at -0.40005 0 90)
			(size 0 0)
			(layers "F.Cu" "F.Mask" "F.Paste")
			(net "P0V8_PEX3_PVCC")
		)
		(pad "2" smd circle
			(at 0.40005 0 90)
			(size 0 0)
			(layers "F.Cu" "F.Mask" "F.Paste")
			(net "GND")
		)
	)
	(footprint ""
		(layer "F.Cu")
		(at 90.4113 -107.29976)
		(property "Reference" "R693"
			(at 0 0 0)
			(layer "F.SilkS")
			(hide yes)
			(effects
				(font
					(size 1.27 1.27)
				)
			)
		)
		(property "Value" ""
			(at 0 0 0)
			(layer "F.Fab")
			(effects
				(font
					(size 1.27 1.27)
				)
			)
		)
		(duplicate_pad_numbers_are_jumpers no)
		(fp_line
			(start -3.937508 -1.8796)
			(end -3.937508 1.8796)
			(stroke
				(width 0.1524)
				(type default)
			)
			(layer "F.SilkS")
		)
		(fp_line
			(start -3.937508 1.8796)
			(end 3.937508 1.8796)
			(stroke
				(width 0.1524)
				(type default)
			)
			(layer "F.SilkS")
		)
		(fp_line
			(start 3.937508 -1.8796)
			(end -3.937508 -1.8796)
			(stroke
				(width 0.1524)
				(type default)
			)
			(layer "F.SilkS")
		)
		(fp_line
			(start 3.937508 1.8796)
			(end 3.937508 -1.8796)
			(stroke
				(width 0.1524)
				(type default)
			)
			(layer "F.SilkS")
		)
		(fp_line
			(start -3.275076 -1.674876)
			(end -3.275076 1.674876)
			(stroke
				(width 0.1)
				(type default)
			)
			(layer "F.Fab")
		)
		(fp_line
			(start -3.275076 1.674876)
			(end 3.275076 1.674876)
			(stroke
				(width 0.1)
				(type default)
			)
			(layer "F.Fab")
		)
		(fp_line
			(start 3.275076 -1.674876)
			(end -3.275076 -1.674876)
			(stroke
				(width 0.1)
				(type default)
			)
			(layer "F.Fab")
		)
		(fp_line
			(start 3.275076 1.674876)
			(end 3.275076 -1.674876)
			(stroke
				(width 0.1)
				(type default)
			)
			(layer "F.Fab")
		)
		(pad "1" smd rect
			(at -2.350008 0)
			(size 2.921 3.5052)
			(layers "F.Cu" "F.Mask" "F.Paste")
			(net "P12V_NIC1")
		)
		(pad "2" smd rect
			(at 2.350008 0)
			(size 2.921 3.5052)
			(layers "F.Cu" "F.Mask" "F.Paste")
			(net "P12V_NIC1_R")
		)
	)
	(footprint ""
		(layer "F.Cu")
		(at 359.156 -191.262 180)
		(property "Reference" "R4639"
			(at 0 0 180)
			(layer "F.SilkS")
			(hide yes)
			(effects
				(font
					(size 1.27 1.27)
				)
			)
		)
		(property "Value" ""
			(at 0 0 180)
			(layer "F.Fab")
			(effects
				(font
					(size 1.27 1.27)
				)
			)
		)
		(duplicate_pad_numbers_are_jumpers no)
		(fp_line
			(start 0.7874 0.4064)
			(end -0.7874 0.4064)
			(stroke
				(width 0.1524)
				(type default)
			)
			(layer "F.SilkS")
		)
		(fp_line
			(start 0.7874 -0.4064)
			(end 0.7874 0.4064)
			(stroke
				(width 0.1524)
				(type default)
			)
			(layer "F.SilkS")
		)
		(fp_line
			(start -0.7874 0.4064)
			(end -0.7874 -0.4064)
			(stroke
				(width 0.1524)
				(type default)
			)
			(layer "F.SilkS")
		)
		(fp_line
			(start -0.7874 -0.4064)
			(end 0.7874 -0.4064)
			(stroke
				(width 0.1524)
				(type default)
			)
			(layer "F.SilkS")
		)
		(fp_line
			(start 0.67945 0.3048)
			(end 0.120396 0.3048)
			(stroke
				(width 0.1)
				(type default)
			)
			(layer "F.Fab")
		)
		(fp_line
			(start 0.67945 -0.3048)
			(end 0.67945 0.3048)
			(stroke
				(width 0.1)
				(type default)
			)
			(layer "F.Fab")
		)
		(fp_line
			(start 0.12065 -0.2794)
			(end 0.12065 -0.3048)
			(stroke
				(width 0.1)
				(type default)
			)
			(layer "F.Fab")
		)
		(fp_line
			(start 0.12065 -0.3048)
			(end 0.67945 -0.3048)
			(stroke
				(width 0.1)
				(type default)
			)
			(layer "F.Fab")
		)
		(fp_line
			(start 0.120396 0.3048)
			(end 0.120396 0.2794)
			(stroke
				(width 0.1)
				(type default)
			)
			(layer "F.Fab")
		)
		(fp_line
			(start 0.120396 0.2794)
			(end -0.12065 0.2794)
			(stroke
				(width 0.1)
				(type default)
			)
			(layer "F.Fab")
		)
		(fp_line
			(start -0.12065 0.3048)
			(end -0.67945 0.3048)
			(stroke
				(width 0.1)
				(type default)
			)
			(layer "F.Fab")
		)
		(fp_line
			(start -0.12065 0.2794)
			(end -0.12065 0.3048)
			(stroke
				(width 0.1)
				(type default)
			)
			(layer "F.Fab")
		)
		(fp_line
			(start -0.12065 -0.2794)
			(end 0.12065 -0.2794)
			(stroke
				(width 0.1)
				(type default)
			)
			(layer "F.Fab")
		)
		(fp_line
			(start -0.12065 -0.305054)
			(end -0.12065 -0.2794)
			(stroke
				(width 0.1)
				(type default)
			)
			(layer "F.Fab")
		)
		(fp_line
			(start -0.67945 0.3048)
			(end -0.67945 -0.305054)
			(stroke
				(width 0.1)
				(type default)
			)
			(layer "F.Fab")
		)
		(fp_line
			(start -0.67945 -0.305054)
			(end -0.12065 -0.305054)
			(stroke
				(width 0.1)
				(type default)
			)
			(layer "F.Fab")
		)
		(pad "1" smd circle
			(at -0.40005 0 180)
			(size 0 0)
			(layers "F.Cu" "F.Mask" "F.Paste")
			(net "PCA9555_1_PEX0_A2")
		)
		(pad "2" smd circle
			(at 0.40005 0 180)
			(size 0 0)
			(layers "F.Cu" "F.Mask" "F.Paste")
			(net "P3V3_AUX")
		)
	)
)
